(kicad_pcb
	(version 20241229)
	(generator "pcbnew")
	(generator_version "9.0")
	(general
		(thickness 1.711)
		(legacy_teardrops no)
	)
	(paper "A4")
	(title_block
		(title "Antmicro Baseboard for Jetson AGX Thor")
		(date "2026-02-18")
		(rev "1.1.0")
		(company "Antmicro Ltd")
		(comment 1 "www.antmicro.com")
		(comment 9 "footprints 93-97 of 1170")
	)
	(layers
		(0 "F.Cu" signal)
		(4 "In1.Cu" signal)
		(6 "In2.Cu" signal)
		(8 "In3.Cu" signal)
		(10 "In4.Cu" jumper)
		(12 "In5.Cu" signal)
		(14 "In6.Cu" signal)
		(16 "In7.Cu" signal)
		(18 "In8.Cu" signal)
		(2 "B.Cu" signal)
		(9 "F.Adhes" user "F.Adhesive")
		(11 "B.Adhes" user "B.Adhesive")
		(13 "F.Paste" user)
		(15 "B.Paste" user)
		(5 "F.SilkS" user "F.Silkscreen")
		(7 "B.SilkS" user "B.Silkscreen")
		(1 "F.Mask" user)
		(3 "B.Mask" user)
		(17 "Dwgs.User" user "User.Drawings")
		(19 "Cmts.User" user "User.Comments")
		(21 "Eco1.User" user "User.Eco1")
		(23 "Eco2.User" user "User.Eco2")
		(25 "Edge.Cuts" user)
		(27 "Margin" user)
		(31 "F.CrtYd" user "F.Courtyard")
		(29 "B.CrtYd" user "B.Courtyard")
		(35 "F.Fab" user)
		(33 "B.Fab" user)
	)
	(footprint "antmicro-footprints:R_0805_2012Metric"
		(layer "F.Cu")
		(at 109.510001 60.719999 -90)
		(property "Reference" "R366"
			(at -1.519999 1.690001 90)
			(layer "F.SilkS")
			(effects
				(font
					(size 0.7 0.7)
					(thickness 0.15)
				)
				(justify right top)
			)
		)
		(property "Value" "R_0R001_0805"
			(at 0 1.8 90)
			(layer "F.Fab")
			(effects
				(font
					(size 0.7 0.7)
					(thickness 0.15)
				)
				(justify right top)
			)
		)
		(property "Datasheet" "https://www.eaton.com/content/dam/eaton/products/electronic-components/resources/data-sheet/eaton-msma-automotive-smd-current-sense-resistor-metal-strip-data-sheet-elx1179.pdf"
			(at 0 0 90)
			(layer "F.Fab")
			(hide yes)
			(effects
				(font
					(size 1.27 1.27)
					(thickness 0.15)
				)
			)
		)
		(property "Description" "Current Sense Resistors - SMD MSMA, 0805 SIZE, 1/2 Watt, 1 mohm, 50 TCR MnCu Metal AEC-Q"
			(at 0 0 90)
			(layer "F.Fab")
			(hide yes)
			(effects
				(font
					(size 1.27 1.27)
					(thickness 0.15)
				)
			)
		)
		(property "MPN" "MSMA0805R0010FSM"
			(at 0 0 270)
			(unlocked yes)
			(layer "F.Fab")
			(hide yes)
			(effects
				(font
					(size 1 1)
					(thickness 0.15)
				)
			)
		)
		(property "Manufacturer" "Eaton"
			(at 0 0 270)
			(unlocked yes)
			(layer "F.Fab")
			(hide yes)
			(effects
				(font
					(size 1 1)
					(thickness 0.15)
				)
			)
		)
		(property "License" "Apache-2.0"
			(at 0 0 270)
			(unlocked yes)
			(layer "F.Fab")
			(hide yes)
			(effects
				(font
					(size 1 1)
					(thickness 0.15)
				)
			)
		)
		(property "Author" "Antmicro"
			(at 0 0 270)
			(unlocked yes)
			(layer "F.Fab")
			(hide yes)
			(effects
				(font
					(size 1 1)
					(thickness 0.15)
				)
			)
		)
		(property "Val" "0R001"
			(at 0 0 270)
			(unlocked yes)
			(layer "F.Fab")
			(hide yes)
			(effects
				(font
					(size 1 1)
					(thickness 0.15)
				)
			)
		)
		(property "Tolerance" "1%"
			(at 0 0 270)
			(unlocked yes)
			(layer "F.Fab")
			(hide yes)
			(effects
				(font
					(size 1 1)
					(thickness 0.15)
				)
			)
		)
		(property "Public" "False"
			(at 0 0 270)
			(unlocked yes)
			(layer "F.Fab")
			(hide yes)
			(effects
				(font
					(size 1 1)
					(thickness 0.15)
				)
			)
		)
		(sheetname "/DCDC/")
		(sheetfile "dcdc.kicad_sch")
		(attr smd)
		(fp_line
			(start -0.32 0.699)
			(end 0.28 0.699001)
			(stroke
				(width 0.15)
				(type solid)
			)
			(layer "F.SilkS")
		)
		(fp_line
			(start -0.3 -0.701)
			(end 0.298 -0.701)
			(stroke
				(width 0.15)
				(type solid)
			)
			(layer "F.SilkS")
		)
		(fp_poly
			(pts
				(xy 1.95 -0.9) (xy -1.95 -0.9) (xy -1.95 0.9) (xy 1.95 0.9)
			)
			(stroke
				(width 0.05)
				(type default)
			)
			(fill no)
			(layer "F.CrtYd")
		)
		(fp_line
			(start -0.951 0.68)
			(end 0.949 0.68)
			(stroke
				(width 0.15)
				(type solid)
			)
			(layer "F.Fab")
		)
		(fp_line
			(start -0.951 -0.677)
			(end -0.951 0.675001)
			(stroke
				(width 0.15)
				(type solid)
			)
			(layer "F.Fab")
		)
		(fp_line
			(start 0.949 -0.677)
			(end 0.949 0.675)
			(stroke
				(width 0.15)
				(type solid)
			)
			(layer "F.Fab")
		)
		(fp_line
			(start -0.951 -0.682)
			(end 0.949 -0.682)
			(stroke
				(width 0.15)
				(type solid)
			)
			(layer "F.Fab")
		)
		(fp_text user "${REFERENCE}"
			(at -1.9 3.1 90)
			(layer "F.Fab")
			(effects
				(font
					(size 0.7 0.7)
					(thickness 0.15)
				)
				(justify right top)
			)
		)
		(fp_text user "License: Apache-2.0"
			(at -1.9 5.75 90)
			(layer "F.Fab")
			(effects
				(font
					(size 0.7 0.7)
					(thickness 0.15)
				)
				(justify right top)
			)
		)
		(fp_text user "Author: Antmicro"
			(at -1.9 4.4 90)
			(layer "F.Fab")
			(effects
				(font
					(size 0.7 0.7)
					(thickness 0.15)
				)
				(justify right top)
			)
		)
		(pad "1" smd roundrect
			(at -1.099999 0 270)
			(size 1.2 1.3)
			(layers "F.Cu" "F.Mask" "F.Paste")
			(roundrect_rratio 0.25)
			(net 1278 "/DCDC/5V_{AON}_OUT")
			(pintype "passive")
		)
		(pad "2" smd roundrect
			(at 1.099999 0 270)
			(size 1.2 1.3)
			(layers "F.Cu" "F.Mask" "F.Paste")
			(roundrect_rratio 0.25)
			(net 491 "+5V_AON")
			(pintype "passive")
		)
	)
	(footprint "antmicro-footprints:R_0402_1005Metric"
		(layer "F.Cu")
		(at 208.1 66.12 90)
		(descr "Resistor SMD 0402")
		(tags "resistor SMD 0402")
		(property "Reference" "R411"
			(at -0.98 -3.2 0)
			(layer "F.SilkS")
			(effects
				(font
					(size 0.7 0.7)
					(thickness 0.15)
				)
				(justify left bottom)
			)
		)
		(property "Value" "R_11k8_0402"
			(at -1.011843 1.772047 90)
			(layer "F.Fab")
			(effects
				(font
					(size 0.7 0.7)
					(thickness 0.15)
				)
				(justify left bottom)
			)
		)
		(property "Datasheet" "https://www.bourns.com/docs/product-datasheets/cr.pdf"
			(at 0 0 90)
			(layer "F.Fab")
			(hide yes)
			(effects
				(font
					(size 1.27 1.27)
					(thickness 0.15)
				)
			)
		)
		(property "Description" "SMD Chip Resistor, 11.8 kohm, ± 1%, 100 mW, 0402 [1005 Metric], Thick Film, Precision"
			(at 0 0 90)
			(layer "F.Fab")
			(hide yes)
			(effects
				(font
					(size 1.27 1.27)
					(thickness 0.15)
				)
			)
		)
		(property "MPN" "CR0402-FX-1182GLF"
			(at 0 0 90)
			(unlocked yes)
			(layer "F.Fab")
			(hide yes)
			(effects
				(font
					(size 1 1)
					(thickness 0.15)
				)
			)
		)
		(property "Manufacturer" "Bourns"
			(at 0 0 90)
			(unlocked yes)
			(layer "F.Fab")
			(hide yes)
			(effects
				(font
					(size 1 1)
					(thickness 0.15)
				)
			)
		)
		(property "License" "Apache-2.0"
			(at 0 0 90)
			(unlocked yes)
			(layer "F.Fab")
			(hide yes)
			(effects
				(font
					(size 1 1)
					(thickness 0.15)
				)
			)
		)
		(property "Author" "Antmicro"
			(at 0 0 90)
			(unlocked yes)
			(layer "F.Fab")
			(hide yes)
			(effects
				(font
					(size 1 1)
					(thickness 0.15)
				)
			)
		)
		(property "Val" "11k8"
			(at 0 0 90)
			(unlocked yes)
			(layer "F.Fab")
			(hide yes)
			(effects
				(font
					(size 1 1)
					(thickness 0.15)
				)
			)
		)
		(property "Tolerance" "1%"
			(at 0 0 90)
			(unlocked yes)
			(layer "F.Fab")
			(hide yes)
			(effects
				(font
					(size 1 1)
					(thickness 0.15)
				)
			)
		)
		(sheetname "/Power/")
		(sheetfile "power.kicad_sch")
		(attr smd)
		(fp_rect
			(start -0.925 -0.47)
			(end 0.925 0.47)
			(stroke
				(width 0.05)
				(type default)
			)
			(fill no)
			(layer "F.CrtYd")
		)
		(fp_rect
			(start -0.5 -0.25)
			(end 0.5 0.25)
			(stroke
				(width 0.15)
				(type solid)
			)
			(fill no)
			(layer "F.Fab")
		)
		(fp_text user "License: Apache-2.0"
			(at -0.95 5.169 90)
			(layer "F.Fab")
			(effects
				(font
					(size 0.7 0.7)
					(thickness 0.15)
				)
				(justify left bottom)
			)
		)
		(fp_text user "Author: Antmicro"
			(at -0.95 4.169 90)
			(layer "F.Fab")
			(effects
				(font
					(size 0.7 0.7)
					(thickness 0.15)
				)
				(justify left bottom)
			)
		)
		(fp_text user "${REFERENCE}"
			(at -0.95 3.168 90)
			(layer "F.Fab")
			(effects
				(font
					(size 0.7 0.7)
					(thickness 0.15)
				)
				(justify left bottom)
			)
		)
		(pad "1" smd roundrect
			(at -0.48 0 90)
			(size 0.59 0.64)
			(layers "F.Cu" "F.Mask" "F.Paste")
			(roundrect_rratio 0.25)
			(net 1 "GND")
			(pintype "passive")
		)
		(pad "2" smd roundrect
			(at 0.48 0 90)
			(size 0.59 0.64)
			(layers "F.Cu" "F.Mask" "F.Paste")
			(roundrect_rratio 0.25)
			(net 1386 "Net-(U9-SET)")
			(pintype "passive")
		)
	)
	(footprint "antmicro-footprints:R_0402_1005Metric"
		(layer "F.Cu")
		(at 214 131.8)
		(descr "Resistor SMD 0402")
		(tags "resistor SMD 0402")
		(property "Reference" "R261"
			(at -0.6 -1.5 0)
			(layer "F.SilkS")
			(effects
				(font
					(size 0.7 0.7)
					(thickness 0.15)
				)
				(justify left bottom)
			)
		)
		(property "Value" "R_43k_0402"
			(at -1.011843 1.772047 0)
			(layer "F.Fab")
			(effects
				(font
					(size 0.7 0.7)
					(thickness 0.15)
				)
				(justify left bottom)
			)
		)
		(property "Datasheet" "https://www.bourns.com/docs/product-datasheets/cr.pdf"
			(at 0 0 0)
			(layer "F.Fab")
			(hide yes)
			(effects
				(font
					(size 1.27 1.27)
					(thickness 0.15)
				)
			)
		)
		(property "Description" "SMD Chip Resistor"
			(at 0 0 0)
			(layer "F.Fab")
			(hide yes)
			(effects
				(font
					(size 1.27 1.27)
					(thickness 0.15)
				)
			)
		)
		(property "MPN" "CR0402-FX-4302GLF"
			(at 0 0 0)
			(unlocked yes)
			(layer "F.Fab")
			(hide yes)
			(effects
				(font
					(size 1 1)
					(thickness 0.15)
				)
			)
		)
		(property "Manufacturer" "Bourns"
			(at 0 0 0)
			(unlocked yes)
			(layer "F.Fab")
			(hide yes)
			(effects
				(font
					(size 1 1)
					(thickness 0.15)
				)
			)
		)
		(property "License" "Apache-2.0"
			(at 0 0 0)
			(unlocked yes)
			(layer "F.Fab")
			(hide yes)
			(effects
				(font
					(size 1 1)
					(thickness 0.15)
				)
			)
		)
		(property "Author" "Antmicro"
			(at 0 0 0)
			(unlocked yes)
			(layer "F.Fab")
			(hide yes)
			(effects
				(font
					(size 1 1)
					(thickness 0.15)
				)
			)
		)
		(property "Val" "43k"
			(at 0 0 0)
			(unlocked yes)
			(layer "F.Fab")
			(hide yes)
			(effects
				(font
					(size 1 1)
					(thickness 0.15)
				)
			)
		)
		(property "Tolerance" "1%"
			(at 0 0 0)
			(unlocked yes)
			(layer "F.Fab")
			(hide yes)
			(effects
				(font
					(size 1 1)
					(thickness 0.15)
				)
			)
		)
		(sheetname "/USB Hub/")
		(sheetfile "usb_hub.kicad_sch")
		(attr smd)
		(fp_rect
			(start -0.925 -0.47)
			(end 0.925 0.47)
			(stroke
				(width 0.05)
				(type default)
			)
			(fill no)
			(layer "F.CrtYd")
		)
		(fp_rect
			(start -0.5 -0.25)
			(end 0.5 0.25)
			(stroke
				(width 0.15)
				(type solid)
			)
			(fill no)
			(layer "F.Fab")
		)
		(fp_text user "${REFERENCE}"
			(at -0.95 3.168 0)
			(layer "F.Fab")
			(effects
				(font
					(size 0.7 0.7)
					(thickness 0.15)
				)
				(justify left bottom)
			)
		)
		(fp_text user "Author: Antmicro"
			(at -0.95 4.169 0)
			(layer "F.Fab")
			(effects
				(font
					(size 0.7 0.7)
					(thickness 0.15)
				)
				(justify left bottom)
			)
		)
		(fp_text user "License: Apache-2.0"
			(at -0.95 5.169 0)
			(layer "F.Fab")
			(effects
				(font
					(size 0.7 0.7)
					(thickness 0.15)
				)
				(justify left bottom)
			)
		)
		(pad "1" smd roundrect
			(at -0.48 0)
			(size 0.59 0.64)
			(layers "F.Cu" "F.Mask" "F.Paste")
			(roundrect_rratio 0.25)
			(net 932 "/USB Hub/USBC4_VBUS_MON")
			(pintype "passive")
		)
		(pad "2" smd roundrect
			(at 0.48 0)
			(size 0.59 0.64)
			(layers "F.Cu" "F.Mask" "F.Paste")
			(roundrect_rratio 0.25)
			(net 115 "/USB Hub/USBC4_VBUS")
			(pintype "passive")
		)
	)
	(footprint "antmicro-footprints:TP_SMD_0.75mm"
		(layer "F.Cu")
		(at 69.289 59.331 90)
		(property "Reference" "TP24"
			(at 0.52 3.19 0)
			(layer "F.SilkS")
			(effects
				(font
					(size 0.7 0.7)
					(thickness 0.15)
				)
				(justify right top)
			)
		)
		(property "Value" "TP_0.75mm_SMD"
			(at 0 1.2 90)
			(layer "F.Fab")
			(effects
				(font
					(size 0.7 0.7)
					(thickness 0.15)
				)
				(justify left bottom)
			)
		)
		(property "Description" "SMT test point"
			(at 0 0 90)
			(layer "F.Fab")
			(hide yes)
			(effects
				(font
					(size 1.27 1.27)
					(thickness 0.15)
				)
			)
		)
		(property "MPN" ""
			(at 0 0 90)
			(unlocked yes)
			(layer "F.Fab")
			(hide yes)
			(effects
				(font
					(size 1 1)
					(thickness 0.15)
				)
			)
		)
		(property "Manufacturer" ""
			(at 0 0 90)
			(unlocked yes)
			(layer "F.Fab")
			(hide yes)
			(effects
				(font
					(size 1 1)
					(thickness 0.15)
				)
			)
		)
		(property "Author" "Antmicro"
			(at 0 0 90)
			(unlocked yes)
			(layer "F.Fab")
			(hide yes)
			(effects
				(font
					(size 1 1)
					(thickness 0.15)
				)
			)
		)
		(property "License" "Apache-2.0"
			(at 0 0 90)
			(unlocked yes)
			(layer "F.Fab")
			(hide yes)
			(effects
				(font
					(size 1 1)
					(thickness 0.15)
				)
			)
		)
		(sheetname "/CSI/")
		(sheetfile "csi.kicad_sch")
		(attr exclude_from_pos_files exclude_from_bom)
		(fp_circle
			(center 0 0)
			(end 0.475 0)
			(stroke
				(width 0.05)
				(type default)
			)
			(fill no)
			(layer "F.CrtYd")
		)
		(fp_text user "License: Apache-2.0"
			(at -0.4 5.101 90)
			(layer "F.Fab")
			(effects
				(font
					(size 0.7 0.7)
					(thickness 0.15)
				)
				(justify left bottom)
			)
		)
		(fp_text user "${REFERENCE}"
			(at -0.4 2.7 90)
			(layer "F.Fab")
			(effects
				(font
					(size 0.7 0.7)
					(thickness 0.15)
				)
				(justify left bottom)
			)
		)
		(fp_text user "Author: Antmicro"
			(at -0.4 3.901 90)
			(layer "F.Fab")
			(effects
				(font
					(size 0.7 0.7)
					(thickness 0.15)
				)
				(justify left bottom)
			)
		)
		(pad "1" smd circle
			(at 0 0 90)
			(size 0.75 0.75)
			(layers "F.Cu" "F.Mask")
			(net 1048 "/CSI/MUX_I2C_5_SCL")
			(pinfunction "1")
			(pintype "passive")
		)
	)
	(footprint "antmicro-footprints:C_0402_1005Metric"
		(layer "F.Cu")
		(at 152.48 114.8)
		(descr "Capacitor SMD 0402")
		(tags "capacitor SMD 0402")
		(property "Reference" "C9"
			(at 0.92 1.6 0)
			(layer "F.SilkS")
			(effects
				(font
					(size 0.7 0.7)
					(thickness 0.15)
				)
				(justify left bottom)
			)
		)
		(property "Value" "C_100n_0402"
			(at -1.022927 2.155213 0)
			(layer "F.Fab")
			(effects
				(font
					(size 0.7 0.7)
					(thickness 0.15)
				)
				(justify left bottom)
			)
		)
		(property "Datasheet" "https://www.murata.com/products/productdetail?partno=GRM155R61H104KE14%23"
			(at 0 0 0)
			(layer "F.Fab")
			(hide yes)
			(effects
				(font
					(size 1.27 1.27)
					(thickness 0.15)
				)
			)
		)
		(property "Description" "SMD Multilayer Ceramic Capacitor, 0.1 µF, 50 V, 0402 [1005 Metric], ± 10%, X5R, GRM Series"
			(at 0 0 0)
			(layer "F.Fab")
			(hide yes)
			(effects
				(font
					(size 1.27 1.27)
					(thickness 0.15)
				)
			)
		)
		(property "Manufacturer" "Murata"
			(at 0 0 0)
			(unlocked yes)
			(layer "F.Fab")
			(hide yes)
			(effects
				(font
					(size 1 1)
					(thickness 0.15)
				)
			)
		)
		(property "MPN" "GRM155R61H104KE14D"
			(at 0 0 0)
			(unlocked yes)
			(layer "F.Fab")
			(hide yes)
			(effects
				(font
					(size 1 1)
					(thickness 0.15)
				)
			)
		)
		(property "Val" "100n"
			(at 0 0 0)
			(unlocked yes)
			(layer "F.Fab")
			(hide yes)
			(effects
				(font
					(size 1 1)
					(thickness 0.15)
				)
			)
		)
		(property "License" "Apache-2.0"
			(at 0 0 0)
			(unlocked yes)
			(layer "F.Fab")
			(hide yes)
			(effects
				(font
					(size 1 1)
					(thickness 0.15)
				)
			)
		)
		(property "Author" "Antmicro"
			(at 0 0 0)
			(unlocked yes)
			(layer "F.Fab")
			(hide yes)
			(effects
				(font
					(size 1 1)
					(thickness 0.15)
				)
			)
		)
		(property "Voltage" "50V"
			(at 0 0 0)
			(unlocked yes)
			(layer "F.Fab")
			(hide yes)
			(effects
				(font
					(size 1 1)
					(thickness 0.15)
				)
			)
		)
		(property "Dielectric" "X5R"
			(at 0 0 0)
			(unlocked yes)
			(layer "F.Fab")
			(hide yes)
			(effects
				(font
					(size 1 1)
					(thickness 0.15)
				)
			)
		)
		(sheetname "/SoM_IO/")
		(sheetfile "som_io.kicad_sch")
		(attr smd)
		(fp_poly
			(pts
				(xy -0.925 -0.47) (xy -0.925 0.47) (xy 0.925 0.47) (xy 0.925 -0.47)
			)
			(stroke
				(width 0.05)
				(type default)
			)
			(fill no)
			(layer "F.CrtYd")
		)
		(fp_line
			(start -0.494 -0.25)
			(end 0.504 -0.25)
			(stroke
				(width 0.15)
				(type solid)
			)
			(layer "F.Fab")
		)
		(fp_line
			(start -0.494 0.248)
			(end -0.494 -0.25)
			(stroke
				(width 0.15)
				(type solid)
			)
			(layer "F.Fab")
		)
		(fp_line
			(start 0.504 -0.25)
			(end 0.504 0.248)
			(stroke
				(width 0.15)
				(type solid)
			)
			(layer "F.Fab")
		)
		(fp_line
			(start 0.504 0.248)
			(end -0.494 0.248)
			(stroke
				(width 0.15)
				(type solid)
			)
			(layer "F.Fab")
		)
		(fp_text user "License: Apache-2.0"
			(at -0.939 5.799 0)
			(layer "F.Fab")
			(effects
				(font
					(size 0.7 0.7)
					(thickness 0.15)
				)
				(justify left bottom)
			)
		)
		(fp_text user "${REFERENCE}"
			(at -0.939 4.599 0)
			(layer "F.Fab")
			(effects
				(font
					(size 0.7 0.7)
					(thickness 0.15)
				)
				(justify left bottom)
			)
		)
		(fp_text user "Author: Antmicro"
			(at -0.939 3.399 0)
			(layer "F.Fab")
			(effects
				(font
					(size 0.7 0.7)
					(thickness 0.15)
				)
				(justify left bottom)
			)
		)
		(pad "1" smd roundrect
			(at -0.48 0)
			(size 0.59 0.64)
			(layers "F.Cu" "F.Mask" "F.Paste")
			(roundrect_rratio 0.25)
			(net 1 "GND")
			(pintype "passive")
		)
		(pad "2" smd roundrect
			(at 0.48 0)
			(size 0.59 0.64)
			(layers "F.Cu" "F.Mask" "F.Paste")
			(roundrect_rratio 0.25)
			(net 11 "+1V8")
			(pintype "passive")
		)
	)
)
